(kicad_pcb
	(version 20260206)
	(generator "pcbnew")
	(generator_version "10.0")
	(general
		(thickness 1.6)
		(legacy_teardrops no)
	)
	(paper "A4")
	(title_block
		(title "03242023_DA0F0TMBIJ0_F0T_Motherboard_J_brd_V01_OCP.brd")
		(comment 1 "Grand Teton / footprints 538-542 of 6105")
	)
	(layers
		(0 "F.Cu" signal "TOP")
		(4 "In1.Cu" signal "GND")
		(6 "In2.Cu" signal "IN1")
		(8 "In3.Cu" signal "GND1")
		(10 "In4.Cu" signal "IN2")
		(12 "In5.Cu" signal "GND2")
		(14 "In6.Cu" signal "IN3")
		(16 "In7.Cu" signal "GND3")
		(18 "In8.Cu" signal "VCC")
		(20 "In9.Cu" signal "VCC1")
		(22 "In10.Cu" signal "GND4")
		(24 "In11.Cu" signal "IN4")
		(26 "In12.Cu" signal "GND5")
		(28 "In13.Cu" signal "IN5")
		(30 "In14.Cu" signal "GND6")
		(32 "In15.Cu" signal "IN6")
		(34 "In16.Cu" signal "GND7")
		(2 "B.Cu" signal "BOTTOM")
		(9 "F.Adhes" user "F.Adhesive")
		(11 "B.Adhes" user "B.Adhesive")
		(13 "F.Paste" user "Package Geometry/Pastemask Top")
		(15 "B.Paste" user "Package Geometry/Pastemask Bottom")
		(5 "F.SilkS" user "Ref Des/Silkscreen Top")
		(7 "B.SilkS" user "Ref Des/Silkscreen Bottom")
		(1 "F.Mask" user "Board Geometry/Soldermask Top")
		(3 "B.Mask" user "Board Geometry/Soldermask Bottom")
		(17 "Dwgs.User" user "User.Drawings")
		(19 "Cmts.User" user "User.Comments")
		(21 "Eco1.User" user "User.Eco1")
		(23 "Eco2.User" user "User.Eco2")
		(25 "Edge.Cuts" user "Board Geometry/Outline")
		(27 "Margin" user)
		(31 "F.CrtYd" user "Package Geometry/Place Bound Top")
		(29 "B.CrtYd" user "Package Geometry/Place Bound Bottom")
		(35 "F.Fab" user "Ref Des/Assembly Top")
		(33 "B.Fab" user "Ref Des/Assembly Bottom")
	)
	(footprint ""
		(layer "F.Cu")
		(at 12.022582 -421.216836 90)
		(property "Reference" "C1713"
			(at 0 0 90)
			(layer "F.SilkS")
			(hide yes)
			(effects
				(font
					(size 1.27 1.27)
				)
			)
		)
		(property "Value" ""
			(at 0 0 90)
			(layer "F.Fab")
			(effects
				(font
					(size 1.27 1.27)
				)
			)
		)
		(duplicate_pad_numbers_are_jumpers no)
		(fp_line
			(start 0.7874 -0.4064)
			(end 0.7874 0.4064)
			(stroke
				(width 0.1524)
				(type default)
			)
			(layer "F.SilkS")
		)
		(fp_line
			(start -0.7874 -0.4064)
			(end 0.7874 -0.4064)
			(stroke
				(width 0.1524)
				(type default)
			)
			(layer "F.SilkS")
		)
		(fp_line
			(start 0.7874 0.4064)
			(end -0.7874 0.4064)
			(stroke
				(width 0.1524)
				(type default)
			)
			(layer "F.SilkS")
		)
		(fp_line
			(start -0.7874 0.4064)
			(end -0.7874 -0.4064)
			(stroke
				(width 0.1524)
				(type default)
			)
			(layer "F.SilkS")
		)
		(fp_line
			(start -0.12065 -0.305054)
			(end -0.12065 -0.2794)
			(stroke
				(width 0.1)
				(type default)
			)
			(layer "F.Fab")
		)
		(fp_line
			(start -0.67945 -0.305054)
			(end -0.12065 -0.305054)
			(stroke
				(width 0.1)
				(type default)
			)
			(layer "F.Fab")
		)
		(fp_line
			(start 0.67945 -0.3048)
			(end 0.67945 0.3048)
			(stroke
				(width 0.1)
				(type default)
			)
			(layer "F.Fab")
		)
		(fp_line
			(start 0.12065 -0.3048)
			(end 0.67945 -0.3048)
			(stroke
				(width 0.1)
				(type default)
			)
			(layer "F.Fab")
		)
		(fp_line
			(start 0.12065 -0.2794)
			(end 0.12065 -0.3048)
			(stroke
				(width 0.1)
				(type default)
			)
			(layer "F.Fab")
		)
		(fp_line
			(start -0.12065 -0.2794)
			(end 0.12065 -0.2794)
			(stroke
				(width 0.1)
				(type default)
			)
			(layer "F.Fab")
		)
		(fp_line
			(start 0.120396 0.2794)
			(end -0.12065 0.2794)
			(stroke
				(width 0.1)
				(type default)
			)
			(layer "F.Fab")
		)
		(fp_line
			(start -0.12065 0.2794)
			(end -0.12065 0.3048)
			(stroke
				(width 0.1)
				(type default)
			)
			(layer "F.Fab")
		)
		(fp_line
			(start 0.67945 0.3048)
			(end 0.120396 0.3048)
			(stroke
				(width 0.1)
				(type default)
			)
			(layer "F.Fab")
		)
		(fp_line
			(start 0.120396 0.3048)
			(end 0.120396 0.2794)
			(stroke
				(width 0.1)
				(type default)
			)
			(layer "F.Fab")
		)
		(fp_line
			(start -0.12065 0.3048)
			(end -0.67945 0.3048)
			(stroke
				(width 0.1)
				(type default)
			)
			(layer "F.Fab")
		)
		(fp_line
			(start -0.67945 0.3048)
			(end -0.67945 -0.305054)
			(stroke
				(width 0.1)
				(type default)
			)
			(layer "F.Fab")
		)
		(pad "1" smd circle
			(at -0.40005 0 90)
			(size 0 0)
			(layers "F.Cu" "F.Mask" "F.Paste")
			(net "P3V3_AUX")
		)
		(pad "2" smd circle
			(at 0.40005 0 90)
			(size 0 0)
			(layers "F.Cu" "F.Mask" "F.Paste")
			(net "GND")
		)
	)
	(footprint ""
		(layer "F.Cu")
		(at 371.672358 -99.185984 90)
		(property "Reference" "U84"
			(at 0.450596 -5.416042 0)
			(unlocked yes)
			(layer "F.SilkS")
			(effects
				(font
					(size 0.7874 0.5842)
					(thickness 0.1524)
				)
				(justify left)
			)
		)
		(property "Value" ""
			(at 0 0 90)
			(layer "F.Fab")
			(effects
				(font
					(size 1.27 1.27)
				)
			)
		)
		(duplicate_pad_numbers_are_jumpers no)
		(fp_line
			(start 2.0066 -2.5527)
			(end 2.0066 2.5527)
			(stroke
				(width 0.1524)
				(type default)
			)
			(layer "F.SilkS")
		)
		(fp_line
			(start 0.5715 -2.5527)
			(end 2.0066 -2.5527)
			(stroke
				(width 0.1524)
				(type default)
			)
			(layer "F.SilkS")
		)
		(fp_line
			(start -0.5715 -2.5527)
			(end 0 -1.9812)
			(stroke
				(width 0.1524)
				(type default)
			)
			(layer "F.SilkS")
		)
		(fp_line
			(start -2.0066 -2.5527)
			(end -0.5715 -2.5527)
			(stroke
				(width 0.1524)
				(type default)
			)
			(layer "F.SilkS")
		)
		(fp_line
			(start 0 -1.9812)
			(end 0.5715 -2.5527)
			(stroke
				(width 0.1524)
				(type default)
			)
			(layer "F.SilkS")
		)
		(fp_line
			(start 2.0066 2.5527)
			(end -2.0066 2.5527)
			(stroke
				(width 0.1524)
				(type default)
			)
			(layer "F.SilkS")
		)
		(fp_line
			(start -2.0066 2.5527)
			(end -2.0066 -2.5527)
			(stroke
				(width 0.1524)
				(type default)
			)
			(layer "F.SilkS")
		)
		(fp_poly
			(pts
				(xy -2.730246 -2.881122) (xy -3.058414 -2.327402) (xy -3.355086 -2.881122)
			)
			(stroke
				(width 0)
				(type default)
			)
			(fill yes)
			(layer "F.SilkS")
		)
		(fp_line
			(start 2.249932 -2.549906)
			(end 2.249932 2.549906)
			(stroke
				(width 0.1)
				(type default)
			)
			(layer "F.Fab")
		)
		(fp_line
			(start -2.249932 -2.549906)
			(end 2.249932 -2.549906)
			(stroke
				(width 0.1)
				(type default)
			)
			(layer "F.Fab")
		)
		(fp_line
			(start 2.249932 2.549906)
			(end -2.249932 2.549906)
			(stroke
				(width 0.1)
				(type default)
			)
			(layer "F.Fab")
		)
		(fp_line
			(start -2.249932 2.549906)
			(end -2.249932 -2.549906)
			(stroke
				(width 0.1)
				(type default)
			)
			(layer "F.Fab")
		)
		(fp_poly
			(pts
				(xy -4.36372 -1.608328) (xy -4.36372 -2.233168) (xy -3.81 -1.905)
			)
			(stroke
				(width 0)
				(type default)
			)
			(fill yes)
			(layer "F.Fab")
		)
		(pad "1" smd rect
			(at -2.921 -1.949958)
			(size 0.3556 1.4986)
			(layers "F.Cu" "F.Mask" "F.Paste")
			(net "PU_GTL2014_BMC_JTAG_DIR_1")
		)
		(pad "2" smd rect
			(at -2.921 -1.299972)
			(size 0.3556 1.4986)
			(layers "F.Cu" "F.Mask" "F.Paste")
			(net "JTAG_DBP_PREQ_R_N")
		)
		(pad "3" smd rect
			(at -2.921 -0.649986)
			(size 0.3556 1.4986)
			(layers "F.Cu" "F.Mask" "F.Paste")
			(net "FM_CPU_FBRK_DEBUG_N")
		)
		(pad "4" smd rect
			(at -2.921 0)
			(size 0.3556 1.4986)
			(layers "F.Cu" "F.Mask" "F.Paste")
			(net "PD_GTL2014_BMC_JTAG_VREF_1")
		)
		(pad "5" smd rect
			(at -2.921 0.649986)
			(size 0.3556 1.4986)
			(layers "F.Cu" "F.Mask" "F.Paste")
			(net "JTAG_DBP_FB_TDI")
		)
		(pad "6" smd rect
			(at -2.921 1.299972)
			(size 0.3556 1.4986)
			(layers "F.Cu" "F.Mask" "F.Paste")
			(net "JTAG_DBP_FB_TMS")
		)
		(pad "7" smd rect
			(at -2.921 1.949958)
			(size 0.3556 1.4986)
			(layers "F.Cu" "F.Mask" "F.Paste")
			(net "GND")
		)
		(pad "8" smd rect
			(at 2.921 1.949958)
			(size 0.3556 1.4986)
			(layers "F.Cu" "F.Mask" "F.Paste")
			(net "GND")
		)
		(pad "9" smd rect
			(at 2.921 1.299972)
			(size 0.3556 1.4986)
			(layers "F.Cu" "F.Mask" "F.Paste")
			(net "JTAG_BMC_DBP_TMS_R")
		)
		(pad "10" smd rect
			(at 2.921 0.649986)
			(size 0.3556 1.4986)
			(layers "F.Cu" "F.Mask" "F.Paste")
			(net "JTAG_BMC_DBP_TDI_R")
		)
		(pad "11" smd rect
			(at 2.921 0)
			(size 0.3556 1.4986)
			(layers "F.Cu" "F.Mask" "F.Paste")
			(net "GND")
		)
		(pad "12" smd rect
			(at 2.921 -0.649986)
			(size 0.3556 1.4986)
			(layers "F.Cu" "F.Mask" "F.Paste")
			(net "FM_BMC_CPU_FBRK_OUT_N")
		)
		(pad "13" smd rect
			(at 2.921 -1.299972)
			(size 0.3556 1.4986)
			(layers "F.Cu" "F.Mask" "F.Paste")
			(net "JTAG_DBP_BMC_PREQ_R1_N")
		)
		(pad "14" smd rect
			(at 2.921 -1.949958)
			(size 0.3556 1.4986)
			(layers "F.Cu" "F.Mask" "F.Paste")
			(net "P3V3_AUX")
		)
	)
	(footprint ""
		(layer "F.Cu")
		(at 466.094318 -39.106094)
		(property "Reference" "Q123"
			(at -1.32334 -2.675128 0)
			(unlocked yes)
			(layer "F.SilkS")
			(effects
				(font
					(size 0.7874 0.5842)
					(thickness 0.1524)
				)
				(justify left)
			)
		)
		(property "Value" ""
			(at 0 0 0)
			(layer "F.Fab")
			(effects
				(font
					(size 1.27 1.27)
				)
			)
		)
		(duplicate_pad_numbers_are_jumpers no)
		(fp_line
			(start -1.332738 -1.100074)
			(end -0.4826 -1.100074)
			(stroke
				(width 0.1524)
				(type default)
			)
			(layer "F.SilkS")
		)
		(fp_line
			(start -1.332738 1.100074)
			(end -1.332738 -1.100074)
			(stroke
				(width 0.1524)
				(type default)
			)
			(layer "F.SilkS")
		)
		(fp_line
			(start -0.4826 -1.100074)
			(end 0 -0.541274)
			(stroke
				(width 0.1524)
				(type default)
			)
			(layer "F.SilkS")
		)
		(fp_line
			(start 0 -0.541274)
			(end 0.4826 -1.100074)
			(stroke
				(width 0.1524)
				(type default)
			)
			(layer "F.SilkS")
		)
		(fp_line
			(start 0.4826 -1.100074)
			(end 1.332738 -1.100074)
			(stroke
				(width 0.1524)
				(type default)
			)
			(layer "F.SilkS")
		)
		(fp_line
			(start 1.332738 -1.100074)
			(end 1.332738 1.100074)
			(stroke
				(width 0.1524)
				(type default)
			)
			(layer "F.SilkS")
		)
		(fp_line
			(start 1.332738 1.100074)
			(end -1.332738 1.100074)
			(stroke
				(width 0.1524)
				(type default)
			)
			(layer "F.SilkS")
		)
		(fp_poly
			(pts
				(xy -0.672338 -2.038096) (xy -1.023366 -1.33604) (xy -1.374394 -2.038096)
			)
			(stroke
				(width 0)
				(type default)
			)
			(fill yes)
			(layer "F.SilkS")
		)
		(fp_line
			(start -0.674878 -1.100074)
			(end 0.674878 -1.100074)
			(stroke
				(width 0.1)
				(type default)
			)
			(layer "F.Fab")
		)
		(fp_line
			(start -0.674878 1.100074)
			(end -0.674878 -1.100074)
			(stroke
				(width 0.1)
				(type default)
			)
			(layer "F.Fab")
		)
		(fp_line
			(start 0.674878 -1.100074)
			(end 0.674878 1.100074)
			(stroke
				(width 0.1)
				(type default)
			)
			(layer "F.Fab")
		)
		(fp_line
			(start 0.674878 1.100074)
			(end -0.674878 1.100074)
			(stroke
				(width 0.1)
				(type default)
			)
			(layer "F.Fab")
		)
		(fp_poly
			(pts
				(xy -2.2352 -0.298958) (xy -2.2352 -1.001014) (xy -1.533144 -0.649986)
			)
			(stroke
				(width 0)
				(type default)
			)
			(fill yes)
			(layer "F.Fab")
		)
		(pad "1" smd rect
			(at -0.94996 -0.649986 90)
			(size 0.4318 0.508)
			(layers "F.Cu" "F.Mask" "F.Paste")
			(net "GND")
		)
		(pad "2" smd rect
			(at -0.94996 0 90)
			(size 0.4318 0.508)
			(layers "F.Cu" "F.Mask" "F.Paste")
			(net "P12V_OCP_EN_1_R")
		)
		(pad "3" smd rect
			(at -0.94996 0.649986 90)
			(size 0.4318 0.508)
			(layers "F.Cu" "F.Mask" "F.Paste")
			(net "P12V_OCP_UV_1_R")
		)
		(pad "4" smd rect
			(at 0.94996 0.649986 90)
			(size 0.4318 0.508)
			(layers "F.Cu" "F.Mask" "F.Paste")
			(net "GND")
		)
		(pad "5" smd rect
			(at 0.94996 0 90)
			(size 0.4318 0.508)
			(layers "F.Cu" "F.Mask" "F.Paste")
			(net "P12V_OCP_1_EN_G")
		)
		(pad "6" smd rect
			(at 0.94996 -0.649986 90)
			(size 0.4318 0.508)
			(layers "F.Cu" "F.Mask" "F.Paste")
			(net "P12V_OCP_1_EN_G")
		)
	)
	(footprint ""
		(layer "F.Cu")
		(at 279.39238 -437.53278)
		(property "Reference" "JP10"
			(at -1.4097 -2.009648 0)
			(unlocked yes)
			(layer "F.SilkS")
			(effects
				(font
					(size 0.7874 0.5842)
					(thickness 0.1524)
				)
				(justify left)
			)
		)
		(property "Value" ""
			(at 0 0 0)
			(layer "F.Fab")
			(effects
				(font
					(size 1.27 1.27)
				)
			)
		)
		(duplicate_pad_numbers_are_jumpers no)
		(fp_line
			(start -1.249934 -1.320038)
			(end 1.249934 -1.320038)
			(stroke
				(width 0.1524)
				(type default)
			)
			(layer "F.SilkS")
		)
		(fp_line
			(start -1.249934 6.400038)
			(end -1.249934 -1.320038)
			(stroke
				(width 0.1524)
				(type default)
			)
			(layer "F.SilkS")
		)
		(fp_line
			(start 1.249934 -1.320038)
			(end 1.249934 6.400038)
			(stroke
				(width 0.1524)
				(type default)
			)
			(layer "F.SilkS")
		)
		(fp_line
			(start 1.249934 6.400038)
			(end -1.249934 6.400038)
			(stroke
				(width 0.1524)
				(type default)
			)
			(layer "F.SilkS")
		)
		(fp_poly
			(pts
				(xy -2.5654 -0.556514) (xy -1.452372 0) (xy -2.5654 0.556514)
			)
			(stroke
				(width 0)
				(type default)
			)
			(fill yes)
			(layer "F.SilkS")
		)
		(fp_line
			(start -1.249934 -1.320038)
			(end 1.249934 -1.320038)
			(stroke
				(width 0.1)
				(type default)
			)
			(layer "F.Fab")
		)
		(fp_line
			(start -1.249934 6.400038)
			(end -1.249934 -1.320038)
			(stroke
				(width 0.1)
				(type default)
			)
			(layer "F.Fab")
		)
		(fp_line
			(start 1.249934 -1.320038)
			(end 1.249934 6.400038)
			(stroke
				(width 0.1)
				(type default)
			)
			(layer "F.Fab")
		)
		(fp_line
			(start 1.249934 6.400038)
			(end -1.249934 6.400038)
			(stroke
				(width 0.1)
				(type default)
			)
			(layer "F.Fab")
		)
		(fp_poly
			(pts
				(xy -2.5654 -0.556514) (xy -1.452372 0) (xy -2.5654 0.556514)
			)
			(stroke
				(width 0)
				(type default)
			)
			(fill yes)
			(layer "F.Fab")
		)
		(fp_text user "3"
			(at -1.778 5.13207 0)
			(unlocked yes)
			(layer "F.SilkS")
			(effects
				(font
					(size 0.7874 0.5842)
					(thickness 0.1524)
				)
			)
		)
		(fp_text user "3"
			(at -1.1557 5.18287 0)
			(unlocked yes)
			(layer "B.SilkS")
			(effects
				(font
					(size 0.7874 0.5842)
					(thickness 0.1524)
				)
				(justify mirror)
			)
		)
		(fp_text user "1"
			(at -1.143 0.02667 0)
			(unlocked yes)
			(layer "B.SilkS")
			(effects
				(font
					(size 0.7874 0.5842)
					(thickness 0.1524)
				)
				(justify mirror)
			)
		)
		(fp_text user "3"
			(at -1.1557 5.18287 0)
			(unlocked yes)
			(layer "B.Fab")
			(effects
				(font
					(size 0.7874 0.5842)
					(thickness 0.1524)
				)
				(justify mirror)
			)
		)
		(fp_text user "1"
			(at -1.143 0.02667 0)
			(unlocked yes)
			(layer "B.Fab")
			(effects
				(font
					(size 0.7874 0.5842)
					(thickness 0.1524)
				)
				(justify mirror)
			)
		)
		(fp_text user "3"
			(at -1.778 5.13207 0)
			(unlocked yes)
			(layer "F.Fab")
			(effects
				(font
					(size 0.7874 0.5842)
					(thickness 0.1524)
				)
			)
		)
		(pad "1" thru_hole rect
			(at 0 0)
			(size 1.5494 1.5494)
			(drill 1.0414)
			(layers "*.Cu" "*.Mask")
			(remove_unused_layers no)
			(net "SMB_SML1_PMBUS_HSC_MODULE_SCL")
			(clearance 0)
			(padstack
				(mode front_inner_back)
				(layer "Inner"
					(shape circle)
					(size 1.5494 1.5494)
					(clearance 0)
				)
				(layer "B.Cu"
					(shape rect)
					(size 1.5494 1.5494)
					(clearance 0)
				)
			)
		)
		(pad "2" thru_hole circle
			(at 0 2.54)
			(size 1.5494 1.5494)
			(drill 1.0414)
			(layers "*.Cu" "*.Mask")
			(remove_unused_layers no)
			(net "SMB_SML1_PMBUS_HSC_MODULE_SDA")
			(clearance 0)
		)
		(pad "3" thru_hole circle
			(at 0 5.08)
			(size 1.5494 1.5494)
			(drill 1.0414)
			(layers "*.Cu" "*.Mask")
			(remove_unused_layers no)
			(net "GND")
			(clearance 0)
		)
	)
	(footprint ""
		(layer "F.Cu")
		(at 220.15704 -47.58436)
		(property "Reference" "U336"
			(at -0.79502 -3.38963 0)
			(unlocked yes)
			(layer "F.SilkS")
			(effects
				(font
					(size 0.7874 0.5842)
					(thickness 0.1524)
				)
				(justify left)
			)
		)
		(property "Value" ""
			(at 0 0 0)
			(layer "F.Fab")
			(effects
				(font
					(size 1.27 1.27)
				)
			)
		)
		(duplicate_pad_numbers_are_jumpers no)
		(fp_line
			(start -1.759712 -1.500124)
			(end 1.759712 -1.500124)
			(stroke
				(width 0.1524)
				(type default)
			)
			(layer "F.SilkS")
		)
		(fp_line
			(start -1.759712 1.500124)
			(end -1.759712 -1.500124)
			(stroke
				(width 0.1524)
				(type default)
			)
			(layer "F.SilkS")
		)
		(fp_line
			(start 1.759712 -1.500124)
			(end 1.759712 1.500124)
			(stroke
				(width 0.1524)
				(type default)
			)
			(layer "F.SilkS")
		)
		(fp_line
			(start 1.759712 1.500124)
			(end -1.759712 1.500124)
			(stroke
				(width 0.1524)
				(type default)
			)
			(layer "F.SilkS")
		)
		(fp_line
			(start -0.700024 -1.500124)
			(end 0.700024 -1.500124)
			(stroke
				(width 0.1)
				(type default)
			)
			(layer "F.Fab")
		)
		(fp_line
			(start -0.700024 1.500124)
			(end -0.700024 -1.500124)
			(stroke
				(width 0.1)
				(type default)
			)
			(layer "F.Fab")
		)
		(fp_line
			(start 0.700024 -1.500124)
			(end 0.700024 1.500124)
			(stroke
				(width 0.1)
				(type default)
			)
			(layer "F.Fab")
		)
		(fp_line
			(start 0.700024 1.500124)
			(end -0.700024 1.500124)
			(stroke
				(width 0.1)
				(type default)
			)
			(layer "F.Fab")
		)
		(pad "1" smd rect
			(at -1.150112 -0.94996 270)
			(size 0.6604 0.9652)
			(layers "F.Cu" "F.Mask" "F.Paste")
			(net "GND")
		)
		(pad "2" smd rect
			(at -1.150112 0.94996 270)
			(size 0.6604 0.9652)
			(layers "F.Cu" "F.Mask" "F.Paste")
			(net "HP_E1S_0_P3V3_PWRGD")
		)
		(pad "3" smd rect
			(at 1.150112 0 270)
			(size 0.6604 0.9652)
			(layers "F.Cu" "F.Mask" "F.Paste")
			(net "P3V3_E1S_0")
		)
	)
)
